# S9S_MB_2U (Grand Teton) — schematic netlist excerpt (pin names and nets, part order shuffled) for the footprints in the layout excerpt that follows; sources: Cadence DE-HDL packaged netlist, KiCad conversion of 03242023_DA0F0TMBIJ0_F0T_Motherboard_J_brd_V01_OCP.brd

PC468  Q_CAP  3300PF 50V 10% X7R  pkg 0402  page 292 : A = SH_PVCCINFAON_CPU1_R ; B = VSENSE_PVCCINFAON_CPU1_DN
R1291  Q_RES  22 1% CHIP  pkg 0402LF  page 154 : A = NCSI_BMC_CRS_DV_R ; B = RMII_OCP_BMC_CRSDV

(kicad_pcb
	(version 20260206)
	(generator "pcbnew")
	(generator_version "10.0")
	(general
		(thickness 1.6)
		(legacy_teardrops no)
	)
	(paper "A4")
	(title_block
		(title "03242023_DA0F0TMBIJ0_F0T_Motherboard_J_brd_V01_OCP.brd")
		(comment 1 "Grand Teton / footprints 1827-1828 of 6105")
	)
	(layers
		(0 "F.Cu" signal "TOP")
		(4 "In1.Cu" signal "GND")
		(6 "In2.Cu" signal "IN1")
		(8 "In3.Cu" signal "GND1")
		(10 "In4.Cu" signal "IN2")
		(12 "In5.Cu" signal "GND2")
		(14 "In6.Cu" signal "IN3")
		(16 "In7.Cu" signal "GND3")
		(18 "In8.Cu" signal "VCC")
		(20 "In9.Cu" signal "VCC1")
		(22 "In10.Cu" signal "GND4")
		(24 "In11.Cu" signal "IN4")
		(26 "In12.Cu" signal "GND5")
		(28 "In13.Cu" signal "IN5")
		(30 "In14.Cu" signal "GND6")
		(32 "In15.Cu" signal "IN6")
		(34 "In16.Cu" signal "GND7")
		(2 "B.Cu" signal "BOTTOM")
		(9 "F.Adhes" user "F.Adhesive")
		(11 "B.Adhes" user "B.Adhesive")
		(13 "F.Paste" user "Package Geometry/Pastemask Top")
		(15 "B.Paste" user "Package Geometry/Pastemask Bottom")
		(5 "F.SilkS" user "Ref Des/Silkscreen Top")
		(7 "B.SilkS" user "Ref Des/Silkscreen Bottom")
		(1 "F.Mask" user "Board Geometry/Soldermask Top")
		(3 "B.Mask" user "Board Geometry/Soldermask Bottom")
		(17 "Dwgs.User" user "User.Drawings")
		(19 "Cmts.User" user "User.Comments")
		(21 "Eco1.User" user "User.Eco1")
		(23 "Eco2.User" user "User.Eco2")
		(25 "Edge.Cuts" user "Board Geometry/Outline")
		(27 "Margin" user)
		(31 "F.CrtYd" user "Package Geometry/Place Bound Top")
		(29 "B.CrtYd" user "Package Geometry/Place Bound Bottom")
		(35 "F.Fab" user "Ref Des/Assembly Top")
		(33 "B.Fab" user "Ref Des/Assembly Bottom")
	)
	(footprint ""
		(layer "F.Cu")
		(at 194.371468 -76.016866)
		(property "Reference" "R1291"
			(at 0 0 0)
			(layer "F.SilkS")
			(hide yes)
			(effects
				(font
					(size 1.27 1.27)
				)
			)
		)
		(property "Value" ""
			(at 0 0 0)
			(layer "F.Fab")
			(effects
				(font
					(size 1.27 1.27)
				)
			)
		)
		(duplicate_pad_numbers_are_jumpers no)
		(fp_line
			(start -0.7874 -0.4064)
			(end 0.7874 -0.4064)
			(stroke
				(width 0.1524)
				(type default)
			)
			(layer "F.SilkS")
		)
		(fp_line
			(start -0.7874 0.4064)
			(end -0.7874 -0.4064)
			(stroke
				(width 0.1524)
				(type default)
			)
			(layer "F.SilkS")
		)
		(fp_line
			(start 0.7874 -0.4064)
			(end 0.7874 0.4064)
			(stroke
				(width 0.1524)
				(type default)
			)
			(layer "F.SilkS")
		)
		(fp_line
			(start 0.7874 0.4064)
			(end -0.7874 0.4064)
			(stroke
				(width 0.1524)
				(type default)
			)
			(layer "F.SilkS")
		)
		(fp_line
			(start -0.67945 -0.305054)
			(end -0.12065 -0.305054)
			(stroke
				(width 0.1)
				(type default)
			)
			(layer "F.Fab")
		)
		(fp_line
			(start -0.67945 0.3048)
			(end -0.67945 -0.305054)
			(stroke
				(width 0.1)
				(type default)
			)
			(layer "F.Fab")
		)
		(fp_line
			(start -0.12065 -0.305054)
			(end -0.12065 -0.2794)
			(stroke
				(width 0.1)
				(type default)
			)
			(layer "F.Fab")
		)
		(fp_line
			(start -0.12065 -0.2794)
			(end 0.12065 -0.2794)
			(stroke
				(width 0.1)
				(type default)
			)
			(layer "F.Fab")
		)
		(fp_line
			(start -0.12065 0.2794)
			(end -0.12065 0.3048)
			(stroke
				(width 0.1)
				(type default)
			)
			(layer "F.Fab")
		)
		(fp_line
			(start -0.12065 0.3048)
			(end -0.67945 0.3048)
			(stroke
				(width 0.1)
				(type default)
			)
			(layer "F.Fab")
		)
		(fp_line
			(start 0.120396 0.2794)
			(end -0.12065 0.2794)
			(stroke
				(width 0.1)
				(type default)
			)
			(layer "F.Fab")
		)
		(fp_line
			(start 0.120396 0.3048)
			(end 0.120396 0.2794)
			(stroke
				(width 0.1)
				(type default)
			)
			(layer "F.Fab")
		)
		(fp_line
			(start 0.12065 -0.3048)
			(end 0.67945 -0.3048)
			(stroke
				(width 0.1)
				(type default)
			)
			(layer "F.Fab")
		)
		(fp_line
			(start 0.12065 -0.2794)
			(end 0.12065 -0.3048)
			(stroke
				(width 0.1)
				(type default)
			)
			(layer "F.Fab")
		)
		(fp_line
			(start 0.67945 -0.3048)
			(end 0.67945 0.3048)
			(stroke
				(width 0.1)
				(type default)
			)
			(layer "F.Fab")
		)
		(fp_line
			(start 0.67945 0.3048)
			(end 0.120396 0.3048)
			(stroke
				(width 0.1)
				(type default)
			)
			(layer "F.Fab")
		)
		(pad "1" smd circle
			(at -0.40005 0)
			(size 0 0)
			(layers "F.Cu" "F.Mask" "F.Paste")
			(net "NCSI_BMC_CRS_DV_R")
		)
		(pad "2" smd circle
			(at 0.40005 0)
			(size 0 0)
			(layers "F.Cu" "F.Mask" "F.Paste")
			(net "RMII_OCP_BMC_CRSDV")
		)
	)
	(footprint ""
		(layer "F.Cu")
		(at 33.7693 -133.444996 180)
		(property "Reference" "PC468"
			(at 0 0 180)
			(layer "F.SilkS")
			(hide yes)
			(effects
				(font
					(size 1.27 1.27)
				)
			)
		)
		(property "Value" ""
			(at 0 0 180)
			(layer "F.Fab")
			(effects
				(font
					(size 1.27 1.27)
				)
			)
		)
		(duplicate_pad_numbers_are_jumpers no)
		(fp_line
			(start 0.7874 0.4064)
			(end -0.7874 0.4064)
			(stroke
				(width 0.1524)
				(type default)
			)
			(layer "F.SilkS")
		)
		(fp_line
			(start 0.7874 -0.4064)
			(end 0.7874 0.4064)
			(stroke
				(width 0.1524)
				(type default)
			)
			(layer "F.SilkS")
		)
		(fp_line
			(start -0.7874 0.4064)
			(end -0.7874 -0.4064)
			(stroke
				(width 0.1524)
				(type default)
			)
			(layer "F.SilkS")
		)
		(fp_line
			(start -0.7874 -0.4064)
			(end 0.7874 -0.4064)
			(stroke
				(width 0.1524)
				(type default)
			)
			(layer "F.SilkS")
		)
		(fp_line
			(start 0.67945 0.3048)
			(end 0.120396 0.3048)
			(stroke
				(width 0.1)
				(type default)
			)
			(layer "F.Fab")
		)
		(fp_line
			(start 0.67945 -0.3048)
			(end 0.67945 0.3048)
			(stroke
				(width 0.1)
				(type default)
			)
			(layer "F.Fab")
		)
		(fp_line
			(start 0.12065 -0.2794)
			(end 0.12065 -0.3048)
			(stroke
				(width 0.1)
				(type default)
			)
			(layer "F.Fab")
		)
		(fp_line
			(start 0.12065 -0.3048)
			(end 0.67945 -0.3048)
			(stroke
				(width 0.1)
				(type default)
			)
			(layer "F.Fab")
		)
		(fp_line
			(start 0.120396 0.3048)
			(end 0.120396 0.2794)
			(stroke
				(width 0.1)
				(type default)
			)
			(layer "F.Fab")
		)
		(fp_line
			(start 0.120396 0.2794)
			(end -0.12065 0.2794)
			(stroke
				(width 0.1)
				(type default)
			)
			(layer "F.Fab")
		)
		(fp_line
			(start -0.12065 0.3048)
			(end -0.67945 0.3048)
			(stroke
				(width 0.1)
				(type default)
			)
			(layer "F.Fab")
		)
		(fp_line
			(start -0.12065 0.2794)
			(end -0.12065 0.3048)
			(stroke
				(width 0.1)
				(type default)
			)
			(layer "F.Fab")
		)
		(fp_line
			(start -0.12065 -0.2794)
			(end 0.12065 -0.2794)
			(stroke
				(width 0.1)
				(type default)
			)
			(layer "F.Fab")
		)
		(fp_line
			(start -0.12065 -0.305054)
			(end -0.12065 -0.2794)
			(stroke
				(width 0.1)
				(type default)
			)
			(layer "F.Fab")
		)
		(fp_line
			(start -0.67945 0.3048)
			(end -0.67945 -0.305054)
			(stroke
				(width 0.1)
				(type default)
			)
			(layer "F.Fab")
		)
		(fp_line
			(start -0.67945 -0.305054)
			(end -0.12065 -0.305054)
			(stroke
				(width 0.1)
				(type default)
			)
			(layer "F.Fab")
		)
		(pad "1" smd circle
			(at -0.40005 0 180)
			(size 0 0)
			(layers "F.Cu" "F.Mask" "F.Paste")
			(net "SH_PVCCINFAON_CPU1_R")
		)
		(pad "2" smd circle
			(at 0.40005 0 180)
			(size 0 0)
			(layers "F.Cu" "F.Mask" "F.Paste")
			(net "VSENSE_PVCCINFAON_CPU1_DN")
		)
	)
)
